# S9S_MB_2U (Grand Teton) — schematic netlist excerpt (pin names and nets, part order shuffled) for the footprints in the layout excerpt that follows; sources: Cadence DE-HDL packaged netlist, KiCad conversion of 03242023_DA0F0TMBIJ0_F0T_Motherboard_J_brd_V01_OCP.brd

PR1767  Q_RES  3.3 1% CHIP  pkg 0402LF  page 285 : A = SW_PVCCIN_CPU1_BOOT1 ; B = SW_PVCCIN_CPU1_BOOT1_R
R635  Q_RES  10K 1% CHIP  pkg 0402LF  page 183 : A = PU_OC3_USB_N ; B = P3V3_AUX

(kicad_pcb
	(version 20260206)
	(generator "pcbnew")
	(generator_version "10.0")
	(general
		(thickness 1.6)
		(legacy_teardrops no)
	)
	(paper "A4")
	(title_block
		(title "03242023_DA0F0TMBIJ0_F0T_Motherboard_J_brd_V01_OCP.brd")
		(comment 1 "Grand Teton / footprints 287-288 of 6105")
	)
	(layers
		(0 "F.Cu" signal "TOP")
		(4 "In1.Cu" signal "GND")
		(6 "In2.Cu" signal "IN1")
		(8 "In3.Cu" signal "GND1")
		(10 "In4.Cu" signal "IN2")
		(12 "In5.Cu" signal "GND2")
		(14 "In6.Cu" signal "IN3")
		(16 "In7.Cu" signal "GND3")
		(18 "In8.Cu" signal "VCC")
		(20 "In9.Cu" signal "VCC1")
		(22 "In10.Cu" signal "GND4")
		(24 "In11.Cu" signal "IN4")
		(26 "In12.Cu" signal "GND5")
		(28 "In13.Cu" signal "IN5")
		(30 "In14.Cu" signal "GND6")
		(32 "In15.Cu" signal "IN6")
		(34 "In16.Cu" signal "GND7")
		(2 "B.Cu" signal "BOTTOM")
		(9 "F.Adhes" user "F.Adhesive")
		(11 "B.Adhes" user "B.Adhesive")
		(13 "F.Paste" user "Package Geometry/Pastemask Top")
		(15 "B.Paste" user "Package Geometry/Pastemask Bottom")
		(5 "F.SilkS" user "Ref Des/Silkscreen Top")
		(7 "B.SilkS" user "Ref Des/Silkscreen Bottom")
		(1 "F.Mask" user "Board Geometry/Soldermask Top")
		(3 "B.Mask" user "Board Geometry/Soldermask Bottom")
		(17 "Dwgs.User" user "User.Drawings")
		(19 "Cmts.User" user "User.Comments")
		(21 "Eco1.User" user "User.Eco1")
		(23 "Eco2.User" user "User.Eco2")
		(25 "Edge.Cuts" user "Board Geometry/Outline")
		(27 "Margin" user)
		(31 "F.CrtYd" user "Package Geometry/Place Bound Top")
		(29 "B.CrtYd" user "Package Geometry/Place Bound Bottom")
		(35 "F.Fab" user "Ref Des/Assembly Top")
		(33 "B.Fab" user "Ref Des/Assembly Bottom")
	)
	(footprint ""
		(layer "F.Cu")
		(at 342.803734 -27.488388 -90)
		(property "Reference" "R635"
			(at 0 0 270)
			(layer "F.SilkS")
			(hide yes)
			(effects
				(font
					(size 1.27 1.27)
				)
			)
		)
		(property "Value" ""
			(at 0 0 270)
			(layer "F.Fab")
			(effects
				(font
					(size 1.27 1.27)
				)
			)
		)
		(duplicate_pad_numbers_are_jumpers no)
		(fp_line
			(start -0.7874 0.4064)
			(end -0.7874 -0.4064)
			(stroke
				(width 0.1524)
				(type default)
			)
			(layer "F.SilkS")
		)
		(fp_line
			(start 0.7874 0.4064)
			(end -0.7874 0.4064)
			(stroke
				(width 0.1524)
				(type default)
			)
			(layer "F.SilkS")
		)
		(fp_line
			(start -0.7874 -0.4064)
			(end 0.7874 -0.4064)
			(stroke
				(width 0.1524)
				(type default)
			)
			(layer "F.SilkS")
		)
		(fp_line
			(start 0.7874 -0.4064)
			(end 0.7874 0.4064)
			(stroke
				(width 0.1524)
				(type default)
			)
			(layer "F.SilkS")
		)
		(fp_line
			(start -0.67945 0.3048)
			(end -0.67945 -0.305054)
			(stroke
				(width 0.1)
				(type default)
			)
			(layer "F.Fab")
		)
		(fp_line
			(start -0.12065 0.3048)
			(end -0.67945 0.3048)
			(stroke
				(width 0.1)
				(type default)
			)
			(layer "F.Fab")
		)
		(fp_line
			(start 0.120396 0.3048)
			(end 0.120396 0.2794)
			(stroke
				(width 0.1)
				(type default)
			)
			(layer "F.Fab")
		)
		(fp_line
			(start 0.67945 0.3048)
			(end 0.120396 0.3048)
			(stroke
				(width 0.1)
				(type default)
			)
			(layer "F.Fab")
		)
		(fp_line
			(start -0.12065 0.2794)
			(end -0.12065 0.3048)
			(stroke
				(width 0.1)
				(type default)
			)
			(layer "F.Fab")
		)
		(fp_line
			(start 0.120396 0.2794)
			(end -0.12065 0.2794)
			(stroke
				(width 0.1)
				(type default)
			)
			(layer "F.Fab")
		)
		(fp_line
			(start -0.12065 -0.2794)
			(end 0.12065 -0.2794)
			(stroke
				(width 0.1)
				(type default)
			)
			(layer "F.Fab")
		)
		(fp_line
			(start 0.12065 -0.2794)
			(end 0.12065 -0.3048)
			(stroke
				(width 0.1)
				(type default)
			)
			(layer "F.Fab")
		)
		(fp_line
			(start 0.12065 -0.3048)
			(end 0.67945 -0.3048)
			(stroke
				(width 0.1)
				(type default)
			)
			(layer "F.Fab")
		)
		(fp_line
			(start 0.67945 -0.3048)
			(end 0.67945 0.3048)
			(stroke
				(width 0.1)
				(type default)
			)
			(layer "F.Fab")
		)
		(fp_line
			(start -0.67945 -0.305054)
			(end -0.12065 -0.305054)
			(stroke
				(width 0.1)
				(type default)
			)
			(layer "F.Fab")
		)
		(fp_line
			(start -0.12065 -0.305054)
			(end -0.12065 -0.2794)
			(stroke
				(width 0.1)
				(type default)
			)
			(layer "F.Fab")
		)
		(pad "1" smd circle
			(at -0.40005 0 270)
			(size 0 0)
			(layers "F.Cu" "F.Mask" "F.Paste")
			(net "PU_OC3_USB_N")
		)
		(pad "2" smd circle
			(at 0.40005 0 270)
			(size 0 0)
			(layers "F.Cu" "F.Mask" "F.Paste")
			(net "P3V3_AUX")
		)
	)
	(footprint ""
		(layer "F.Cu")
		(at 98.045016 -338.180172 90)
		(property "Reference" "PR1767"
			(at 0 0 90)
			(layer "F.SilkS")
			(hide yes)
			(effects
				(font
					(size 1.27 1.27)
				)
			)
		)
		(property "Value" ""
			(at 0 0 90)
			(layer "F.Fab")
			(effects
				(font
					(size 1.27 1.27)
				)
			)
		)
		(duplicate_pad_numbers_are_jumpers no)
		(fp_line
			(start 0.7874 -0.4064)
			(end 0.7874 0.4064)
			(stroke
				(width 0.1524)
				(type default)
			)
			(layer "F.SilkS")
		)
		(fp_line
			(start -0.7874 -0.4064)
			(end 0.7874 -0.4064)
			(stroke
				(width 0.1524)
				(type default)
			)
			(layer "F.SilkS")
		)
		(fp_line
			(start 0.7874 0.4064)
			(end -0.7874 0.4064)
			(stroke
				(width 0.1524)
				(type default)
			)
			(layer "F.SilkS")
		)
		(fp_line
			(start -0.7874 0.4064)
			(end -0.7874 -0.4064)
			(stroke
				(width 0.1524)
				(type default)
			)
			(layer "F.SilkS")
		)
		(fp_line
			(start -0.12065 -0.305054)
			(end -0.12065 -0.2794)
			(stroke
				(width 0.1)
				(type default)
			)
			(layer "F.Fab")
		)
		(fp_line
			(start -0.67945 -0.305054)
			(end -0.12065 -0.305054)
			(stroke
				(width 0.1)
				(type default)
			)
			(layer "F.Fab")
		)
		(fp_line
			(start 0.67945 -0.3048)
			(end 0.67945 0.3048)
			(stroke
				(width 0.1)
				(type default)
			)
			(layer "F.Fab")
		)
		(fp_line
			(start 0.12065 -0.3048)
			(end 0.67945 -0.3048)
			(stroke
				(width 0.1)
				(type default)
			)
			(layer "F.Fab")
		)
		(fp_line
			(start 0.12065 -0.2794)
			(end 0.12065 -0.3048)
			(stroke
				(width 0.1)
				(type default)
			)
			(layer "F.Fab")
		)
		(fp_line
			(start -0.12065 -0.2794)
			(end 0.12065 -0.2794)
			(stroke
				(width 0.1)
				(type default)
			)
			(layer "F.Fab")
		)
		(fp_line
			(start 0.120396 0.2794)
			(end -0.12065 0.2794)
			(stroke
				(width 0.1)
				(type default)
			)
			(layer "F.Fab")
		)
		(fp_line
			(start -0.12065 0.2794)
			(end -0.12065 0.3048)
			(stroke
				(width 0.1)
				(type default)
			)
			(layer "F.Fab")
		)
		(fp_line
			(start 0.67945 0.3048)
			(end 0.120396 0.3048)
			(stroke
				(width 0.1)
				(type default)
			)
			(layer "F.Fab")
		)
		(fp_line
			(start 0.120396 0.3048)
			(end 0.120396 0.2794)
			(stroke
				(width 0.1)
				(type default)
			)
			(layer "F.Fab")
		)
		(fp_line
			(start -0.12065 0.3048)
			(end -0.67945 0.3048)
			(stroke
				(width 0.1)
				(type default)
			)
			(layer "F.Fab")
		)
		(fp_line
			(start -0.67945 0.3048)
			(end -0.67945 -0.305054)
			(stroke
				(width 0.1)
				(type default)
			)
			(layer "F.Fab")
		)
		(pad "1" smd circle
			(at -0.40005 0 90)
			(size 0 0)
			(layers "F.Cu" "F.Mask" "F.Paste")
			(net "SW_PVCCIN_CPU1_BOOT1")
		)
		(pad "2" smd circle
			(at 0.40005 0 90)
			(size 0 0)
			(layers "F.Cu" "F.Mask" "F.Paste")
			(net "SW_PVCCIN_CPU1_BOOT1_R")
		)
	)
)
